# TIMECARD (Time Appliance Project (Time Card)) — schematic netlist excerpt (pin names and nets, part order shuffled) for the footprints in the layout excerpt that follows; sources: Cadence DE-HDL packaged netlist, KiCad conversion of R4006-B0001-02_R01.brd

C78  CAPACITOR  0.1UF 25V 10%  pkg SMC_0402R_H022  page 22 : \1\ = XP5R0V_VCC_ANT ; \2\ = SG
C154  CAPACITOR  4.7UF 6.3V 20%  pkg SMC_0402R_H026  page 14 : \1\ = XP3R3V_FPGA ; \2\ = SG

(kicad_pcb
	(version 20260206)
	(generator "pcbnew")
	(generator_version "10.0")
	(general
		(thickness 1.6)
		(legacy_teardrops no)
	)
	(paper "A4")
	(title_block
		(title "timecard-production-celestica-r4006 — R4006-B0001-02_R01.brd")
		(comment 1 "Time Appliance Project (Time Card) / footprints 954-955 of 1113")
	)
	(layers
		(0 "F.Cu" signal "TOP")
		(4 "In1.Cu" signal "L02_GND1")
		(6 "In2.Cu" signal "L03_SIG1")
		(8 "In3.Cu" signal "L04_GND2")
		(10 "In4.Cu" signal "L05_VCC1")
		(12 "In5.Cu" signal "L06_VCC2")
		(14 "In6.Cu" signal "L07_GND3")
		(16 "In7.Cu" signal "L08_SIG2")
		(18 "In8.Cu" signal "L09_GND4")
		(2 "B.Cu" signal "BOTTOM")
		(9 "F.Adhes" user "F.Adhesive")
		(11 "B.Adhes" user "B.Adhesive")
		(13 "F.Paste" user "Package Geometry/Pastemask Top")
		(15 "B.Paste" user "Package Geometry/Pastemask Bottom")
		(5 "F.SilkS" user "Ref Des/Silkscreen Top")
		(7 "B.SilkS" user "Ref Des/Silkscreen Bottom")
		(1 "F.Mask" user "Board Geometry/Soldermask Top")
		(3 "B.Mask" user "Board Geometry/Soldermask Bottom")
		(17 "Dwgs.User" user "User.Drawings")
		(19 "Cmts.User" user "User.Comments")
		(21 "Eco1.User" user "User.Eco1")
		(23 "Eco2.User" user "User.Eco2")
		(25 "Edge.Cuts" user "Board Geometry/Outline")
		(27 "Margin" user)
		(31 "F.CrtYd" user "Package Geometry/Place Bound Top")
		(29 "B.CrtYd" user "Package Geometry/Place Bound Bottom")
		(35 "F.Fab" user "Ref Des/Assembly Top")
		(33 "B.Fab" user "Ref Des/Assembly Bottom")
	)
	(footprint ""
		(layer "B.Cu")
		(at 127.889 -98.425 90)
		(property "Reference" "C78"
			(at -2.794 -0.42037 270)
			(unlocked yes)
			(layer "B.SilkS")
			(effects
				(font
					(size 0.7874 0.5842)
					(thickness 0.1524)
				)
				(justify mirror)
			)
		)
		(property "Value" "VAL*"
			(at -0.0762 2.067306 90)
			(unlocked yes)
			(layer "B.Fab")
			(hide yes)
			(effects
				(font
					(size 0.7874 0.5842)
					(thickness 0.1524)
				)
				(justify mirror)
			)
		)
		(property "Device Type" "CAPACITOR-G105-0B104-EK,0.1UF,A"
			(at -0.0508 1.127506 90)
			(unlocked yes)
			(layer "B.Fab")
			(hide yes)
			(effects
				(font
					(size 0.7874 0.5842)
					(thickness 0.1524)
				)
				(justify mirror)
			)
		)
		(property "User Part Number" "PARTNUM*"
			(at -0.1016 4.023106 90)
			(unlocked yes)
			(layer "Cmts.User")
			(hide yes)
			(effects
				(font
					(size 0.7874 0.5842)
					(thickness 0.1524)
				)
				(justify mirror)
			)
		)
		(property "Tolerance" "TOL*"
			(at -0.0762 3.032506 90)
			(unlocked yes)
			(layer "Cmts.User")
			(hide yes)
			(effects
				(font
					(size 0.7874 0.5842)
					(thickness 0.1524)
				)
				(justify mirror)
			)
		)
		(duplicate_pad_numbers_are_jumpers no)
		(fp_line
			(start 1.143 -0.5588)
			(end 1.143 0.5588)
			(stroke
				(width 0.1)
				(type default)
			)
			(layer "B.SilkS")
		)
		(fp_line
			(start -1.143 -0.5588)
			(end 1.143 -0.5588)
			(stroke
				(width 0.1)
				(type default)
			)
			(layer "B.SilkS")
		)
		(fp_line
			(start 1.143 0.5588)
			(end -1.143 0.5588)
			(stroke
				(width 0.1)
				(type default)
			)
			(layer "B.SilkS")
		)
		(fp_line
			(start -1.143 0.5588)
			(end -1.143 -0.5588)
			(stroke
				(width 0.1)
				(type default)
			)
			(layer "B.SilkS")
		)
		(fp_rect
			(start -1.143 -0.5588)
			(end 1.143 0.5588)
			(stroke
				(width 0)
				(type default)
			)
			(fill no)
			(layer "B.CrtYd")
		)
		(fp_line
			(start 0.508 -0.3048)
			(end 0.508 0.3048)
			(stroke
				(width 0.1)
				(type default)
			)
			(layer "B.Fab")
		)
		(fp_line
			(start -0.508 -0.3048)
			(end 0.508 -0.3048)
			(stroke
				(width 0.1)
				(type default)
			)
			(layer "B.Fab")
		)
		(fp_line
			(start 0.508 0.3048)
			(end -0.508 0.3048)
			(stroke
				(width 0.1)
				(type default)
			)
			(layer "B.Fab")
		)
		(fp_line
			(start -0.508 0.3048)
			(end -0.508 -0.3048)
			(stroke
				(width 0.1)
				(type default)
			)
			(layer "B.Fab")
		)
		(pad "1" smd rect
			(at 0.5334 0 270)
			(size 0.7112 0.6096)
			(layers "B.Cu" "B.Mask" "B.Paste")
			(net "XP5R0V_VCC_ANT")
		)
		(pad "2" smd rect
			(at -0.5334 0 270)
			(size 0.7112 0.6096)
			(layers "B.Cu" "B.Mask" "B.Paste")
			(net "SG")
		)
		(zone
			(layer "B.Cu")
			(hatch none 0.5)
			(connect_pads
				(clearance 0)
			)
			(min_thickness 0.25)
			(keepout
				(tracks allowed)
				(vias not_allowed)
				(pads allowed)
				(copperpour not_allowed)
				(footprints allowed)
			)
			(placement
				(enabled no)
				(sheetname "")
			)
			(fill
				(thermal_gap 0.5)
				(thermal_bridge_width 0.5)
				(island_removal_mode 0)
			)
			(polygon
				(pts
					(xy 127.5842 -98.3488) (xy 128.1938 -98.3488) (xy 128.1938 -98.5012) (xy 127.5842 -98.5012)
				)
			)
		)
	)
	(footprint ""
		(layer "B.Cu")
		(at 118.847108 -54.323234 -90)
		(property "Reference" "C154"
			(at -3.461766 0.014478 270)
			(unlocked yes)
			(layer "B.SilkS")
			(effects
				(font
					(size 0.7874 0.5842)
					(thickness 0.1524)
				)
				(justify mirror)
			)
		)
		(property "Value" "VAL*"
			(at 0 3.718306 270)
			(unlocked yes)
			(layer "B.Fab")
			(hide yes)
			(effects
				(font
					(size 0.7874 0.5842)
					(thickness 0.127)
				)
				(justify mirror)
			)
		)
		(property "Device Type" "CAPACITOR-G105-0F475-BM,4.7UF,A"
			(at 0 1.432306 270)
			(unlocked yes)
			(layer "B.Fab")
			(hide yes)
			(effects
				(font
					(size 0.7874 0.5842)
					(thickness 0.127)
				)
				(justify mirror)
			)
		)
		(property "User Part Number" "PARTNUM*"
			(at 0 2.575306 270)
			(unlocked yes)
			(layer "Cmts.User")
			(hide yes)
			(effects
				(font
					(size 0.7874 0.5842)
					(thickness 0.127)
				)
				(justify mirror)
			)
		)
		(property "Tolerance" "TOL*"
			(at 0 4.861306 270)
			(unlocked yes)
			(layer "Cmts.User")
			(hide yes)
			(effects
				(font
					(size 0.7874 0.5842)
					(thickness 0.127)
				)
				(justify mirror)
			)
		)
		(duplicate_pad_numbers_are_jumpers no)
		(fp_line
			(start -0.970026 0.4699)
			(end 0.970026 0.4699)
			(stroke
				(width 0.1)
				(type default)
			)
			(layer "B.SilkS")
		)
		(fp_line
			(start 0.970026 0.4699)
			(end 0.970026 -0.4699)
			(stroke
				(width 0.1)
				(type default)
			)
			(layer "B.SilkS")
		)
		(fp_line
			(start -0.970026 -0.4699)
			(end -0.970026 0.4699)
			(stroke
				(width 0.1)
				(type default)
			)
			(layer "B.SilkS")
		)
		(fp_line
			(start 0.970026 -0.4699)
			(end -0.970026 -0.4699)
			(stroke
				(width 0.1)
				(type default)
			)
			(layer "B.SilkS")
		)
		(fp_poly
			(pts
				(xy 0.970026 0.4699) (xy -0.970026 0.4699) (xy -0.970026 -0.4699) (xy 0.970026 -0.4699)
			)
			(stroke
				(width 0)
				(type default)
			)
			(fill no)
			(layer "B.CrtYd")
		)
		(fp_line
			(start -0.508 0.3048)
			(end 0.508 0.3048)
			(stroke
				(width 0.1)
				(type default)
			)
			(layer "B.Fab")
		)
		(fp_line
			(start 0.508 0.3048)
			(end 0.508 -0.3048)
			(stroke
				(width 0.1)
				(type default)
			)
			(layer "B.Fab")
		)
		(fp_line
			(start -0.508 -0.3048)
			(end -0.508 0.3048)
			(stroke
				(width 0.1)
				(type default)
			)
			(layer "B.Fab")
		)
		(fp_line
			(start 0.508 -0.3048)
			(end -0.508 -0.3048)
			(stroke
				(width 0.1)
				(type default)
			)
			(layer "B.Fab")
		)
		(pad "1" smd circle
			(at 0.500126 0 90)
			(size 0.635 0.635)
			(layers "B.Cu" "B.Mask" "B.Paste")
			(net "XP3R3V_FPGA")
		)
		(pad "2" smd circle
			(at -0.500126 0 90)
			(size 0.635 0.635)
			(layers "B.Cu" "B.Mask" "B.Paste")
			(net "SG")
		)
	)
)
